# TIMECARD (Time Appliance Project (Time Card)) — schematic netlist excerpt (pin names and nets, part order shuffled) for the footprints in the layout excerpt that follows; sources: Cadence DE-HDL packaged netlist, KiCad conversion of R4006-B0001-02_R01.brd

R114  RESISTOR  4.7KOHM 1%  pkg SMC_0402R_H016  page 22 : \1\ = GPS_RST_N ; \2\ = SG
R365  RESISTOR  4.7KOHM 1%  pkg SMC_0402R_H016  page 23 : \1\ = XP3R3V_FPGA ; \2\ = SMA3_SIG_OUT_BF_EN_N

(kicad_pcb
	(version 20260206)
	(generator "pcbnew")
	(generator_version "10.0")
	(general
		(thickness 1.6)
		(legacy_teardrops no)
	)
	(paper "A4")
	(title_block
		(title "timecard-production-celestica-r4006 — R4006-B0001-02_R01.brd")
		(comment 1 "Time Appliance Project (Time Card) / footprints 345-346 of 1113")
	)
	(layers
		(0 "F.Cu" signal "TOP")
		(4 "In1.Cu" signal "L02_GND1")
		(6 "In2.Cu" signal "L03_SIG1")
		(8 "In3.Cu" signal "L04_GND2")
		(10 "In4.Cu" signal "L05_VCC1")
		(12 "In5.Cu" signal "L06_VCC2")
		(14 "In6.Cu" signal "L07_GND3")
		(16 "In7.Cu" signal "L08_SIG2")
		(18 "In8.Cu" signal "L09_GND4")
		(2 "B.Cu" signal "BOTTOM")
		(9 "F.Adhes" user "F.Adhesive")
		(11 "B.Adhes" user "B.Adhesive")
		(13 "F.Paste" user "Package Geometry/Pastemask Top")
		(15 "B.Paste" user "Package Geometry/Pastemask Bottom")
		(5 "F.SilkS" user "Ref Des/Silkscreen Top")
		(7 "B.SilkS" user "Ref Des/Silkscreen Bottom")
		(1 "F.Mask" user "Board Geometry/Soldermask Top")
		(3 "B.Mask" user "Board Geometry/Soldermask Bottom")
		(17 "Dwgs.User" user "User.Drawings")
		(19 "Cmts.User" user "User.Comments")
		(21 "Eco1.User" user "User.Eco1")
		(23 "Eco2.User" user "User.Eco2")
		(25 "Edge.Cuts" user "Board Geometry/Outline")
		(27 "Margin" user)
		(31 "F.CrtYd" user "Package Geometry/Place Bound Top")
		(29 "B.CrtYd" user "Package Geometry/Place Bound Bottom")
		(35 "F.Fab" user "Ref Des/Assembly Top")
		(33 "B.Fab" user "Ref Des/Assembly Bottom")
	)
	(footprint ""
		(layer "F.Cu")
		(at 14.732 -37.211 -90)
		(property "Reference" "R365"
			(at 1.27 3.77063 90)
			(unlocked yes)
			(layer "F.SilkS")
			(effects
				(font
					(size 0.7874 0.5842)
					(thickness 0.1524)
				)
			)
		)
		(property "Value" "VAL*"
			(at 0.02032 2.13233 270)
			(unlocked yes)
			(layer "F.Fab")
			(hide yes)
			(effects
				(font
					(size 0.7874 0.5842)
					(thickness 0.1524)
				)
			)
		)
		(property "Tolerance" "TOL*"
			(at 0.044704 3.05435 270)
			(unlocked yes)
			(layer "Cmts.User")
			(hide yes)
			(effects
				(font
					(size 0.7874 0.5842)
					(thickness 0.1524)
				)
			)
		)
		(property "User Part Number" "PARTNUM*"
			(at 0.02032 4.024884 270)
			(unlocked yes)
			(layer "Cmts.User")
			(hide yes)
			(effects
				(font
					(size 0.7874 0.5842)
					(thickness 0.1524)
				)
			)
		)
		(property "Device Type" "RESISTOR-G155-14701-01,4.7KOHMA"
			(at 0.008382 1.210564 270)
			(unlocked yes)
			(layer "F.Fab")
			(hide yes)
			(effects
				(font
					(size 0.7874 0.5842)
					(thickness 0.1524)
				)
			)
		)
		(duplicate_pad_numbers_are_jumpers no)
		(fp_line
			(start -1.143 0.5588)
			(end 1.143 0.5588)
			(stroke
				(width 0.1)
				(type default)
			)
			(layer "F.SilkS")
		)
		(fp_line
			(start 1.143 0.5588)
			(end 1.143 -0.5588)
			(stroke
				(width 0.1)
				(type default)
			)
			(layer "F.SilkS")
		)
		(fp_line
			(start -1.143 -0.5588)
			(end -1.143 0.5588)
			(stroke
				(width 0.1)
				(type default)
			)
			(layer "F.SilkS")
		)
		(fp_line
			(start 1.143 -0.5588)
			(end -1.143 -0.5588)
			(stroke
				(width 0.1)
				(type default)
			)
			(layer "F.SilkS")
		)
		(fp_rect
			(start 1.143 0.5588)
			(end -1.143 -0.5588)
			(stroke
				(width 0)
				(type default)
			)
			(fill no)
			(layer "F.CrtYd")
		)
		(fp_line
			(start -0.508 0.3048)
			(end 0.508 0.3048)
			(stroke
				(width 0.1)
				(type default)
			)
			(layer "F.Fab")
		)
		(fp_line
			(start 0.508 0.3048)
			(end 0.508 -0.3048)
			(stroke
				(width 0.1)
				(type default)
			)
			(layer "F.Fab")
		)
		(fp_line
			(start -0.508 -0.3048)
			(end -0.508 0.3048)
			(stroke
				(width 0.1)
				(type default)
			)
			(layer "F.Fab")
		)
		(fp_line
			(start 0.508 -0.3048)
			(end -0.508 -0.3048)
			(stroke
				(width 0.1)
				(type default)
			)
			(layer "F.Fab")
		)
		(pad "1" smd rect
			(at -0.5334 0 270)
			(size 0.7112 0.6096)
			(layers "F.Cu" "F.Mask" "F.Paste")
			(net "XP3R3V_FPGA")
		)
		(pad "2" smd rect
			(at 0.5334 0 270)
			(size 0.7112 0.6096)
			(layers "F.Cu" "F.Mask" "F.Paste")
			(net "SMA3_SIG_OUT_BF_EN_N")
		)
		(zone
			(layer "F.Cu")
			(hatch none 0.5)
			(connect_pads
				(clearance 0)
			)
			(min_thickness 0.25)
			(keepout
				(tracks not_allowed)
				(vias allowed)
				(pads allowed)
				(copperpour not_allowed)
				(footprints allowed)
			)
			(placement
				(enabled no)
				(sheetname "")
			)
			(fill
				(thermal_gap 0.5)
				(thermal_bridge_width 0.5)
				(island_removal_mode 0)
			)
			(polygon
				(pts
					(xy 14.4272 -37.1348) (xy 15.0368 -37.1348) (xy 15.0368 -37.2872) (xy 14.4272 -37.2872)
				)
			)
		)
		(zone
			(layer "F.Cu")
			(hatch none 0.5)
			(connect_pads
				(clearance 0)
			)
			(min_thickness 0.25)
			(keepout
				(tracks allowed)
				(vias not_allowed)
				(pads allowed)
				(copperpour not_allowed)
				(footprints allowed)
			)
			(placement
				(enabled no)
				(sheetname "")
			)
			(fill
				(thermal_gap 0.5)
				(thermal_bridge_width 0.5)
				(island_removal_mode 0)
			)
			(polygon
				(pts
					(xy 14.4272 -37.1348) (xy 15.0368 -37.1348) (xy 15.0368 -37.2872) (xy 14.4272 -37.2872)
				)
			)
		)
	)
	(footprint ""
		(layer "F.Cu")
		(at 120.269 -89.535 -90)
		(property "Reference" "R114"
			(at 3.429 0.08763 90)
			(unlocked yes)
			(layer "F.SilkS")
			(effects
				(font
					(size 0.7874 0.5842)
					(thickness 0.1524)
				)
			)
		)
		(property "Value" "VAL*"
			(at 0.02032 2.13233 270)
			(unlocked yes)
			(layer "F.Fab")
			(hide yes)
			(effects
				(font
					(size 0.7874 0.5842)
					(thickness 0.1524)
				)
			)
		)
		(property "Device Type" "RESISTOR-G155-14701-01,4.7KOHMA"
			(at 0.008382 1.210564 270)
			(unlocked yes)
			(layer "F.Fab")
			(hide yes)
			(effects
				(font
					(size 0.7874 0.5842)
					(thickness 0.1524)
				)
			)
		)
		(property "User Part Number" "PARTNUM*"
			(at 0.02032 4.024884 270)
			(unlocked yes)
			(layer "Cmts.User")
			(hide yes)
			(effects
				(font
					(size 0.7874 0.5842)
					(thickness 0.1524)
				)
			)
		)
		(property "Tolerance" "TOL*"
			(at 0.044704 3.05435 270)
			(unlocked yes)
			(layer "Cmts.User")
			(hide yes)
			(effects
				(font
					(size 0.7874 0.5842)
					(thickness 0.1524)
				)
			)
		)
		(duplicate_pad_numbers_are_jumpers no)
		(fp_line
			(start -1.143 0.5588)
			(end 1.143 0.5588)
			(stroke
				(width 0.1)
				(type default)
			)
			(layer "F.SilkS")
		)
		(fp_line
			(start 1.143 0.5588)
			(end 1.143 -0.5588)
			(stroke
				(width 0.1)
				(type default)
			)
			(layer "F.SilkS")
		)
		(fp_line
			(start -1.143 -0.5588)
			(end -1.143 0.5588)
			(stroke
				(width 0.1)
				(type default)
			)
			(layer "F.SilkS")
		)
		(fp_line
			(start 1.143 -0.5588)
			(end -1.143 -0.5588)
			(stroke
				(width 0.1)
				(type default)
			)
			(layer "F.SilkS")
		)
		(fp_rect
			(start 1.143 -0.5588)
			(end -1.143 0.5588)
			(stroke
				(width 0)
				(type default)
			)
			(fill no)
			(layer "F.CrtYd")
		)
		(fp_line
			(start -0.508 0.3048)
			(end 0.508 0.3048)
			(stroke
				(width 0.1)
				(type default)
			)
			(layer "F.Fab")
		)
		(fp_line
			(start 0.508 0.3048)
			(end 0.508 -0.3048)
			(stroke
				(width 0.1)
				(type default)
			)
			(layer "F.Fab")
		)
		(fp_line
			(start -0.508 -0.3048)
			(end -0.508 0.3048)
			(stroke
				(width 0.1)
				(type default)
			)
			(layer "F.Fab")
		)
		(fp_line
			(start 0.508 -0.3048)
			(end -0.508 -0.3048)
			(stroke
				(width 0.1)
				(type default)
			)
			(layer "F.Fab")
		)
		(pad "1" smd rect
			(at -0.5334 0 270)
			(size 0.7112 0.6096)
			(layers "F.Cu" "F.Mask" "F.Paste")
			(net "GPS_RST_N")
		)
		(pad "2" smd rect
			(at 0.5334 0 270)
			(size 0.7112 0.6096)
			(layers "F.Cu" "F.Mask" "F.Paste")
			(net "SG")
		)
		(zone
			(layer "F.Cu")
			(hatch none 0.5)
			(connect_pads
				(clearance 0)
			)
			(min_thickness 0.25)
			(keepout
				(tracks allowed)
				(vias not_allowed)
				(pads allowed)
				(copperpour not_allowed)
				(footprints allowed)
			)
			(placement
				(enabled no)
				(sheetname "")
			)
			(fill
				(thermal_gap 0.5)
				(thermal_bridge_width 0.5)
				(island_removal_mode 0)
			)
			(polygon
				(pts
					(xy 120.5738 -89.4588) (xy 120.5738 -89.6112) (xy 119.9642 -89.6112) (xy 119.9642 -89.4588)
				)
			)
		)
	)
)
